(kicad_pcb
	(version 20260206)
	(generator "pcbnew")
	(generator_version "10.0")
	(general
		(thickness 1.6)
		(legacy_teardrops no)
	)
	(paper "A4")
	(title_block
		(title "01162023_DA0F0TEBIF0_F0T_Expander_BD_F_brd_V02_OCP.brd")
		(comment 1 "Grand Teton / footprints 2029-2034 of 9728")
	)
	(layers
		(0 "F.Cu" signal "TOP")
		(4 "In1.Cu" signal "GND")
		(6 "In2.Cu" signal "VCC")
		(8 "In3.Cu" signal "VCC1")
		(10 "In4.Cu" signal "GND1")
		(12 "In5.Cu" signal "IN1")
		(14 "In6.Cu" signal "GND2")
		(16 "In7.Cu" signal "IN2")
		(18 "In8.Cu" signal "GND3")
		(20 "In9.Cu" signal "IN3")
		(22 "In10.Cu" signal "GND4")
		(24 "In11.Cu" signal "IN4")
		(26 "In12.Cu" signal "GND5")
		(28 "In13.Cu" signal "IN5")
		(30 "In14.Cu" signal "GND6")
		(32 "In15.Cu" signal "IN6")
		(34 "In16.Cu" signal "GND7")
		(2 "B.Cu" signal "BOTTOM")
		(9 "F.Adhes" user "F.Adhesive")
		(11 "B.Adhes" user "B.Adhesive")
		(13 "F.Paste" user "Package Geometry/Pastemask Top")
		(15 "B.Paste" user "Package Geometry/Pastemask Bottom")
		(5 "F.SilkS" user "Ref Des/Silkscreen Top")
		(7 "B.SilkS" user "Ref Des/Silkscreen Bottom")
		(1 "F.Mask" user "Board Geometry/Soldermask Top")
		(3 "B.Mask" user "Board Geometry/Soldermask Bottom")
		(17 "Dwgs.User" user "User.Drawings")
		(19 "Cmts.User" user "User.Comments")
		(21 "Eco1.User" user "User.Eco1")
		(23 "Eco2.User" user "User.Eco2")
		(25 "Edge.Cuts" user "Board Geometry/Outline")
		(27 "Margin" user)
		(31 "F.CrtYd" user "Package Geometry/Place Bound Top")
		(29 "B.CrtYd" user "Package Geometry/Place Bound Bottom")
		(35 "F.Fab" user "Ref Des/Assembly Top")
		(33 "B.Fab" user "Ref Des/Assembly Bottom")
	)
	(footprint ""
		(layer "F.Cu")
		(at 15.18539 -307.26888)
		(property "Reference" "PC219"
			(at 0 0 0)
			(layer "F.SilkS")
			(hide yes)
			(effects
				(font
					(size 1.27 1.27)
				)
			)
		)
		(property "Value" ""
			(at 0 0 0)
			(layer "F.Fab")
			(effects
				(font
					(size 1.27 1.27)
				)
			)
		)
		(duplicate_pad_numbers_are_jumpers no)
		(fp_line
			(start -0.7874 -0.4064)
			(end 0.7874 -0.4064)
			(stroke
				(width 0.1524)
				(type default)
			)
			(layer "F.SilkS")
		)
		(fp_line
			(start -0.7874 0.4064)
			(end -0.7874 -0.4064)
			(stroke
				(width 0.1524)
				(type default)
			)
			(layer "F.SilkS")
		)
		(fp_line
			(start 0.7874 -0.4064)
			(end 0.7874 0.4064)
			(stroke
				(width 0.1524)
				(type default)
			)
			(layer "F.SilkS")
		)
		(fp_line
			(start 0.7874 0.4064)
			(end -0.7874 0.4064)
			(stroke
				(width 0.1524)
				(type default)
			)
			(layer "F.SilkS")
		)
		(fp_line
			(start -0.67945 -0.305054)
			(end -0.12065 -0.305054)
			(stroke
				(width 0.1)
				(type default)
			)
			(layer "F.Fab")
		)
		(fp_line
			(start -0.67945 0.3048)
			(end -0.67945 -0.305054)
			(stroke
				(width 0.1)
				(type default)
			)
			(layer "F.Fab")
		)
		(fp_line
			(start -0.12065 -0.305054)
			(end -0.12065 -0.2794)
			(stroke
				(width 0.1)
				(type default)
			)
			(layer "F.Fab")
		)
		(fp_line
			(start -0.12065 -0.2794)
			(end 0.12065 -0.2794)
			(stroke
				(width 0.1)
				(type default)
			)
			(layer "F.Fab")
		)
		(fp_line
			(start -0.12065 0.2794)
			(end -0.12065 0.3048)
			(stroke
				(width 0.1)
				(type default)
			)
			(layer "F.Fab")
		)
		(fp_line
			(start -0.12065 0.3048)
			(end -0.67945 0.3048)
			(stroke
				(width 0.1)
				(type default)
			)
			(layer "F.Fab")
		)
		(fp_line
			(start 0.120396 0.2794)
			(end -0.12065 0.2794)
			(stroke
				(width 0.1)
				(type default)
			)
			(layer "F.Fab")
		)
		(fp_line
			(start 0.120396 0.3048)
			(end 0.120396 0.2794)
			(stroke
				(width 0.1)
				(type default)
			)
			(layer "F.Fab")
		)
		(fp_line
			(start 0.12065 -0.3048)
			(end 0.67945 -0.3048)
			(stroke
				(width 0.1)
				(type default)
			)
			(layer "F.Fab")
		)
		(fp_line
			(start 0.12065 -0.2794)
			(end 0.12065 -0.3048)
			(stroke
				(width 0.1)
				(type default)
			)
			(layer "F.Fab")
		)
		(fp_line
			(start 0.67945 -0.3048)
			(end 0.67945 0.3048)
			(stroke
				(width 0.1)
				(type default)
			)
			(layer "F.Fab")
		)
		(fp_line
			(start 0.67945 0.3048)
			(end 0.120396 0.3048)
			(stroke
				(width 0.1)
				(type default)
			)
			(layer "F.Fab")
		)
		(pad "1" smd circle
			(at -0.40005 0)
			(size 0 0)
			(layers "F.Cu" "F.Mask" "F.Paste")
			(net "P1V25_PEX0_FB")
		)
		(pad "2" smd circle
			(at 0.40005 0)
			(size 0 0)
			(layers "F.Cu" "F.Mask" "F.Paste")
			(net "SH_P1V25_PEX0_FB_P")
		)
	)
	(footprint ""
		(layer "F.Cu")
		(at 344.612976 -85.255354 180)
		(property "Reference" "R1178"
			(at 0 0 180)
			(layer "F.SilkS")
			(hide yes)
			(effects
				(font
					(size 1.27 1.27)
				)
			)
		)
		(property "Value" ""
			(at 0 0 180)
			(layer "F.Fab")
			(effects
				(font
					(size 1.27 1.27)
				)
			)
		)
		(duplicate_pad_numbers_are_jumpers no)
		(fp_line
			(start -0.7874 -0.4064)
			(end 0.7874 -0.4064)
			(stroke
				(width 0.1524)
				(type default)
			)
			(layer "F.SilkS")
		)
		(fp_line
			(start 0.67945 0.3048)
			(end 0.120396 0.3048)
			(stroke
				(width 0.1)
				(type default)
			)
			(layer "F.Fab")
		)
		(fp_line
			(start 0.67945 -0.3048)
			(end 0.67945 0.3048)
			(stroke
				(width 0.1)
				(type default)
			)
			(layer "F.Fab")
		)
		(fp_line
			(start 0.12065 -0.2794)
			(end 0.12065 -0.3048)
			(stroke
				(width 0.1)
				(type default)
			)
			(layer "F.Fab")
		)
		(fp_line
			(start 0.12065 -0.3048)
			(end 0.67945 -0.3048)
			(stroke
				(width 0.1)
				(type default)
			)
			(layer "F.Fab")
		)
		(fp_line
			(start 0.120396 0.3048)
			(end 0.120396 0.2794)
			(stroke
				(width 0.1)
				(type default)
			)
			(layer "F.Fab")
		)
		(fp_line
			(start 0.120396 0.2794)
			(end -0.12065 0.2794)
			(stroke
				(width 0.1)
				(type default)
			)
			(layer "F.Fab")
		)
		(fp_line
			(start -0.12065 0.3048)
			(end -0.67945 0.3048)
			(stroke
				(width 0.1)
				(type default)
			)
			(layer "F.Fab")
		)
		(fp_line
			(start -0.12065 0.2794)
			(end -0.12065 0.3048)
			(stroke
				(width 0.1)
				(type default)
			)
			(layer "F.Fab")
		)
		(fp_line
			(start -0.12065 -0.2794)
			(end 0.12065 -0.2794)
			(stroke
				(width 0.1)
				(type default)
			)
			(layer "F.Fab")
		)
		(fp_line
			(start -0.12065 -0.305054)
			(end -0.12065 -0.2794)
			(stroke
				(width 0.1)
				(type default)
			)
			(layer "F.Fab")
		)
		(fp_line
			(start -0.67945 0.3048)
			(end -0.67945 -0.305054)
			(stroke
				(width 0.1)
				(type default)
			)
			(layer "F.Fab")
		)
		(fp_line
			(start -0.67945 -0.305054)
			(end -0.12065 -0.305054)
			(stroke
				(width 0.1)
				(type default)
			)
			(layer "F.Fab")
		)
		(pad "1" smd circle
			(at -0.40005 0 180)
			(size 0 0)
			(layers "F.Cu" "F.Mask" "F.Paste")
			(net "CLK_100M_DB800ZL_SSD12_R_DP")
		)
		(pad "2" smd circle
			(at 0.40005 0 180)
			(size 0 0)
			(layers "F.Cu" "F.Mask" "F.Paste")
			(net "CLK_100M_DB800ZL_SSD12_DP")
		)
	)
	(footprint ""
		(layer "F.Cu")
		(at 446.42532 -42.849038 180)
		(property "Reference" "R678"
			(at 0 0 180)
			(layer "F.SilkS")
			(hide yes)
			(effects
				(font
					(size 1.27 1.27)
				)
			)
		)
		(property "Value" ""
			(at 0 0 180)
			(layer "F.Fab")
			(effects
				(font
					(size 1.27 1.27)
				)
			)
		)
		(duplicate_pad_numbers_are_jumpers no)
		(fp_line
			(start 0.7874 0.4064)
			(end -0.7874 0.4064)
			(stroke
				(width 0.1524)
				(type default)
			)
			(layer "F.SilkS")
		)
		(fp_line
			(start 0.7874 -0.4064)
			(end 0.7874 0.4064)
			(stroke
				(width 0.1524)
				(type default)
			)
			(layer "F.SilkS")
		)
		(fp_line
			(start -0.7874 0.4064)
			(end -0.7874 -0.4064)
			(stroke
				(width 0.1524)
				(type default)
			)
			(layer "F.SilkS")
		)
		(fp_line
			(start -0.7874 -0.4064)
			(end 0.7874 -0.4064)
			(stroke
				(width 0.1524)
				(type default)
			)
			(layer "F.SilkS")
		)
		(fp_line
			(start 0.67945 0.3048)
			(end 0.120396 0.3048)
			(stroke
				(width 0.1)
				(type default)
			)
			(layer "F.Fab")
		)
		(fp_line
			(start 0.67945 -0.3048)
			(end 0.67945 0.3048)
			(stroke
				(width 0.1)
				(type default)
			)
			(layer "F.Fab")
		)
		(fp_line
			(start 0.12065 -0.2794)
			(end 0.12065 -0.3048)
			(stroke
				(width 0.1)
				(type default)
			)
			(layer "F.Fab")
		)
		(fp_line
			(start 0.12065 -0.3048)
			(end 0.67945 -0.3048)
			(stroke
				(width 0.1)
				(type default)
			)
			(layer "F.Fab")
		)
		(fp_line
			(start 0.120396 0.3048)
			(end 0.120396 0.2794)
			(stroke
				(width 0.1)
				(type default)
			)
			(layer "F.Fab")
		)
		(fp_line
			(start 0.120396 0.2794)
			(end -0.12065 0.2794)
			(stroke
				(width 0.1)
				(type default)
			)
			(layer "F.Fab")
		)
		(fp_line
			(start -0.12065 0.3048)
			(end -0.67945 0.3048)
			(stroke
				(width 0.1)
				(type default)
			)
			(layer "F.Fab")
		)
		(fp_line
			(start -0.12065 0.2794)
			(end -0.12065 0.3048)
			(stroke
				(width 0.1)
				(type default)
			)
			(layer "F.Fab")
		)
		(fp_line
			(start -0.12065 -0.2794)
			(end 0.12065 -0.2794)
			(stroke
				(width 0.1)
				(type default)
			)
			(layer "F.Fab")
		)
		(fp_line
			(start -0.12065 -0.305054)
			(end -0.12065 -0.2794)
			(stroke
				(width 0.1)
				(type default)
			)
			(layer "F.Fab")
		)
		(fp_line
			(start -0.67945 0.3048)
			(end -0.67945 -0.305054)
			(stroke
				(width 0.1)
				(type default)
			)
			(layer "F.Fab")
		)
		(fp_line
			(start -0.67945 -0.305054)
			(end -0.12065 -0.305054)
			(stroke
				(width 0.1)
				(type default)
			)
			(layer "F.Fab")
		)
		(pad "1" smd circle
			(at -0.40005 0 180)
			(size 0 0)
			(layers "F.Cu" "F.Mask" "F.Paste")
			(net "P12V_SSD15_R")
		)
		(pad "2" smd circle
			(at 0.40005 0 180)
			(size 0 0)
			(layers "F.Cu" "F.Mask" "F.Paste")
			(net "P12V_SSD15_VIN_P")
		)
	)
	(footprint ""
		(layer "F.Cu")
		(at 309.264304 -29.079952 180)
		(property "Reference" "R6208"
			(at 0 0 180)
			(layer "F.SilkS")
			(hide yes)
			(effects
				(font
					(size 1.27 1.27)
				)
			)
		)
		(property "Value" ""
			(at 0 0 180)
			(layer "F.Fab")
			(effects
				(font
					(size 1.27 1.27)
				)
			)
		)
		(duplicate_pad_numbers_are_jumpers no)
		(fp_line
			(start 0.7874 0.4064)
			(end -0.7874 0.4064)
			(stroke
				(width 0.1524)
				(type default)
			)
			(layer "F.SilkS")
		)
		(fp_line
			(start 0.7874 -0.4064)
			(end 0.7874 0.4064)
			(stroke
				(width 0.1524)
				(type default)
			)
			(layer "F.SilkS")
		)
		(fp_line
			(start -0.7874 0.4064)
			(end -0.7874 -0.4064)
			(stroke
				(width 0.1524)
				(type default)
			)
			(layer "F.SilkS")
		)
		(fp_line
			(start -0.7874 -0.4064)
			(end 0.7874 -0.4064)
			(stroke
				(width 0.1524)
				(type default)
			)
			(layer "F.SilkS")
		)
		(fp_line
			(start 0.67945 0.3048)
			(end 0.120396 0.3048)
			(stroke
				(width 0.1)
				(type default)
			)
			(layer "F.Fab")
		)
		(fp_line
			(start 0.67945 -0.3048)
			(end 0.67945 0.3048)
			(stroke
				(width 0.1)
				(type default)
			)
			(layer "F.Fab")
		)
		(fp_line
			(start 0.12065 -0.2794)
			(end 0.12065 -0.3048)
			(stroke
				(width 0.1)
				(type default)
			)
			(layer "F.Fab")
		)
		(fp_line
			(start 0.12065 -0.3048)
			(end 0.67945 -0.3048)
			(stroke
				(width 0.1)
				(type default)
			)
			(layer "F.Fab")
		)
		(fp_line
			(start 0.120396 0.3048)
			(end 0.120396 0.2794)
			(stroke
				(width 0.1)
				(type default)
			)
			(layer "F.Fab")
		)
		(fp_line
			(start 0.120396 0.2794)
			(end -0.12065 0.2794)
			(stroke
				(width 0.1)
				(type default)
			)
			(layer "F.Fab")
		)
		(fp_line
			(start -0.12065 0.3048)
			(end -0.67945 0.3048)
			(stroke
				(width 0.1)
				(type default)
			)
			(layer "F.Fab")
		)
		(fp_line
			(start -0.12065 0.2794)
			(end -0.12065 0.3048)
			(stroke
				(width 0.1)
				(type default)
			)
			(layer "F.Fab")
		)
		(fp_line
			(start -0.12065 -0.2794)
			(end 0.12065 -0.2794)
			(stroke
				(width 0.1)
				(type default)
			)
			(layer "F.Fab")
		)
		(fp_line
			(start -0.12065 -0.305054)
			(end -0.12065 -0.2794)
			(stroke
				(width 0.1)
				(type default)
			)
			(layer "F.Fab")
		)
		(fp_line
			(start -0.67945 0.3048)
			(end -0.67945 -0.305054)
			(stroke
				(width 0.1)
				(type default)
			)
			(layer "F.Fab")
		)
		(fp_line
			(start -0.67945 -0.305054)
			(end -0.12065 -0.305054)
			(stroke
				(width 0.1)
				(type default)
			)
			(layer "F.Fab")
		)
		(pad "1" smd circle
			(at -0.40005 0 180)
			(size 0 0)
			(layers "F.Cu" "F.Mask" "F.Paste")
			(net "GND")
		)
		(pad "2" smd circle
			(at 0.40005 0 180)
			(size 0 0)
			(layers "F.Cu" "F.Mask" "F.Paste")
			(net "SSD10_PWRDIS_R")
		)
	)
	(footprint ""
		(layer "F.Cu")
		(at 85.933788 -302.88738 90)
		(property "Reference" "R6660"
			(at 0 0 90)
			(layer "F.SilkS")
			(hide yes)
			(effects
				(font
					(size 1.27 1.27)
				)
			)
		)
		(property "Value" ""
			(at 0 0 90)
			(layer "F.Fab")
			(effects
				(font
					(size 1.27 1.27)
				)
			)
		)
		(duplicate_pad_numbers_are_jumpers no)
		(fp_line
			(start 0.7874 -0.4064)
			(end 0.7874 0.4064)
			(stroke
				(width 0.1524)
				(type default)
			)
			(layer "F.SilkS")
		)
		(fp_line
			(start -0.7874 -0.4064)
			(end 0.7874 -0.4064)
			(stroke
				(width 0.1524)
				(type default)
			)
			(layer "F.SilkS")
		)
		(fp_line
			(start 0.7874 0.4064)
			(end -0.7874 0.4064)
			(stroke
				(width 0.1524)
				(type default)
			)
			(layer "F.SilkS")
		)
		(fp_line
			(start -0.7874 0.4064)
			(end -0.7874 -0.4064)
			(stroke
				(width 0.1524)
				(type default)
			)
			(layer "F.SilkS")
		)
		(fp_line
			(start -0.12065 -0.305054)
			(end -0.12065 -0.2794)
			(stroke
				(width 0.1)
				(type default)
			)
			(layer "F.Fab")
		)
		(fp_line
			(start -0.67945 -0.305054)
			(end -0.12065 -0.305054)
			(stroke
				(width 0.1)
				(type default)
			)
			(layer "F.Fab")
		)
		(fp_line
			(start 0.67945 -0.3048)
			(end 0.67945 0.3048)
			(stroke
				(width 0.1)
				(type default)
			)
			(layer "F.Fab")
		)
		(fp_line
			(start 0.12065 -0.3048)
			(end 0.67945 -0.3048)
			(stroke
				(width 0.1)
				(type default)
			)
			(layer "F.Fab")
		)
		(fp_line
			(start 0.12065 -0.2794)
			(end 0.12065 -0.3048)
			(stroke
				(width 0.1)
				(type default)
			)
			(layer "F.Fab")
		)
		(fp_line
			(start -0.12065 -0.2794)
			(end 0.12065 -0.2794)
			(stroke
				(width 0.1)
				(type default)
			)
			(layer "F.Fab")
		)
		(fp_line
			(start 0.120396 0.2794)
			(end -0.12065 0.2794)
			(stroke
				(width 0.1)
				(type default)
			)
			(layer "F.Fab")
		)
		(fp_line
			(start -0.12065 0.2794)
			(end -0.12065 0.3048)
			(stroke
				(width 0.1)
				(type default)
			)
			(layer "F.Fab")
		)
		(fp_line
			(start 0.67945 0.3048)
			(end 0.120396 0.3048)
			(stroke
				(width 0.1)
				(type default)
			)
			(layer "F.Fab")
		)
		(fp_line
			(start 0.120396 0.3048)
			(end 0.120396 0.2794)
			(stroke
				(width 0.1)
				(type default)
			)
			(layer "F.Fab")
		)
		(fp_line
			(start -0.12065 0.3048)
			(end -0.67945 0.3048)
			(stroke
				(width 0.1)
				(type default)
			)
			(layer "F.Fab")
		)
		(fp_line
			(start -0.67945 0.3048)
			(end -0.67945 -0.305054)
			(stroke
				(width 0.1)
				(type default)
			)
			(layer "F.Fab")
		)
		(pad "1" smd circle
			(at -0.40005 0 90)
			(size 0 0)
			(layers "F.Cu" "F.Mask" "F.Paste")
			(net "SMB_PEX0_SLAVE1_SCL")
		)
		(pad "2" smd circle
			(at 0.40005 0 90)
			(size 0 0)
			(layers "F.Cu" "F.Mask" "F.Paste")
			(net "SMB_PEX0_R_SCL")
		)
	)
	(footprint ""
		(layer "F.Cu")
		(at 440.652662 -311.197244 135)
		(property "Reference" "R1449"
			(at 0 0 135)
			(layer "F.SilkS")
			(hide yes)
			(effects
				(font
					(size 1.27 1.27)
				)
			)
		)
		(property "Value" ""
			(at 0 0 135)
			(layer "F.Fab")
			(effects
				(font
					(size 1.27 1.27)
				)
			)
		)
		(duplicate_pad_numbers_are_jumpers no)
		(fp_line
			(start 0.787389 -0.406267)
			(end 0.787389 0.406267)
			(stroke
				(width 0.1524)
				(type default)
			)
			(layer "F.SilkS")
		)
		(fp_line
			(start 0.787389 0.406267)
			(end -0.787389 0.406267)
			(stroke
				(width 0.1524)
				(type default)
			)
			(layer "F.SilkS")
		)
		(fp_line
			(start -0.787389 -0.406267)
			(end 0.787389 -0.406267)
			(stroke
				(width 0.1524)
				(type default)
			)
			(layer "F.SilkS")
		)
		(fp_line
			(start -0.787389 0.406267)
			(end -0.787389 -0.406267)
			(stroke
				(width 0.1524)
				(type default)
			)
			(layer "F.SilkS")
		)
		(fp_line
			(start 0.679446 -0.30479)
			(end 0.679446 0.30479)
			(stroke
				(width 0.1)
				(type default)
			)
			(layer "F.Fab")
		)
		(fp_line
			(start 0.120515 -0.30479)
			(end 0.679446 -0.30479)
			(stroke
				(width 0.1)
				(type default)
			)
			(layer "F.Fab")
		)
		(fp_line
			(start 0.120695 -0.279466)
			(end 0.120515 -0.30479)
			(stroke
				(width 0.1)
				(type default)
			)
			(layer "F.Fab")
		)
		(fp_line
			(start 0.679446 0.30479)
			(end 0.120515 0.30479)
			(stroke
				(width 0.1)
				(type default)
			)
			(layer "F.Fab")
		)
		(fp_line
			(start -0.120695 -0.304969)
			(end -0.120695 -0.279466)
			(stroke
				(width 0.1)
				(type default)
			)
			(layer "F.Fab")
		)
		(fp_line
			(start -0.120695 -0.279466)
			(end 0.120695 -0.279466)
			(stroke
				(width 0.1)
				(type default)
			)
			(layer "F.Fab")
		)
		(fp_line
			(start 0.120335 0.279466)
			(end -0.120695 0.279466)
			(stroke
				(width 0.1)
				(type default)
			)
			(layer "F.Fab")
		)
		(fp_line
			(start 0.120515 0.30479)
			(end 0.120335 0.279466)
			(stroke
				(width 0.1)
				(type default)
			)
			(layer "F.Fab")
		)
		(fp_line
			(start -0.679446 -0.305149)
			(end -0.120695 -0.304969)
			(stroke
				(width 0.1)
				(type default)
			)
			(layer "F.Fab")
		)
		(fp_line
			(start -0.120695 0.279466)
			(end -0.120515 0.30479)
			(stroke
				(width 0.1)
				(type default)
			)
			(layer "F.Fab")
		)
		(fp_line
			(start -0.120515 0.30479)
			(end -0.679446 0.30479)
			(stroke
				(width 0.1)
				(type default)
			)
			(layer "F.Fab")
		)
		(fp_line
			(start -0.679446 0.30479)
			(end -0.679446 -0.305149)
			(stroke
				(width 0.1)
				(type default)
			)
			(layer "F.Fab")
		)
		(pad "1" smd circle
			(at -0.40005 0 135)
			(size 0 0)
			(layers "F.Cu" "F.Mask" "F.Paste")
			(net "GND")
		)
		(pad "2" smd circle
			(at 0.40005 0 135)
			(size 0 0)
			(layers "F.Cu" "F.Mask" "F.Paste")
			(net "PEX3_SPARE5")
		)
	)
)
